(kicad_pcb
	(version 20260206)
	(generator "pcbnew")
	(generator_version "10.0")
	(general
		(thickness 1.6)
		(legacy_teardrops no)
	)
	(paper "A4")
	(title_block
		(title "9052_F0T_PDB_Converter_Brick_F_V03_1208_1600_OCP.brd")
		(comment 1 "Grand Teton / footprints 255-263 of 578")
	)
	(layers
		(0 "F.Cu" signal "TOP")
		(4 "In1.Cu" signal "GND")
		(6 "In2.Cu" signal "IN1")
		(8 "In3.Cu" signal "GND1")
		(10 "In4.Cu" signal "VCC")
		(12 "In5.Cu" signal "VCC1")
		(14 "In6.Cu" signal "GND2")
		(16 "In7.Cu" signal "IN2")
		(18 "In8.Cu" signal "GND3")
		(2 "B.Cu" signal "BOTTOM")
		(9 "F.Adhes" user "F.Adhesive")
		(11 "B.Adhes" user "B.Adhesive")
		(13 "F.Paste" user "Package Geometry/Pastemask Top")
		(15 "B.Paste" user "Package Geometry/Pastemask Bottom")
		(5 "F.SilkS" user "Ref Des/Silkscreen Top")
		(7 "B.SilkS" user "Ref Des/Silkscreen Bottom")
		(1 "F.Mask" user "Board Geometry/Soldermask Top")
		(3 "B.Mask" user "Board Geometry/Soldermask Bottom")
		(17 "Dwgs.User" user "User.Drawings")
		(19 "Cmts.User" user "User.Comments")
		(21 "Eco1.User" user "User.Eco1")
		(23 "Eco2.User" user "User.Eco2")
		(25 "Edge.Cuts" user "Board Geometry/Outline")
		(27 "Margin" user)
		(31 "F.CrtYd" user "Package Geometry/Place Bound Top")
		(29 "B.CrtYd" user "Package Geometry/Place Bound Bottom")
		(35 "F.Fab" user "Ref Des/Assembly Top")
		(33 "B.Fab" user "Ref Des/Assembly Bottom")
	)
	(footprint ""
		(layer "F.Cu")
		(at 176.784 -8.128)
		(property "Reference" "PR90"
			(at 0 0 0)
			(layer "F.SilkS")
			(hide yes)
			(effects
				(font
					(size 1.27 1.27)
				)
			)
		)
		(property "Value" ""
			(at 0 0 0)
			(layer "F.Fab")
			(effects
				(font
					(size 1.27 1.27)
				)
			)
		)
		(duplicate_pad_numbers_are_jumpers no)
		(fp_line
			(start -0.7874 -0.4064)
			(end 0.7874 -0.4064)
			(stroke
				(width 0.1524)
				(type default)
			)
			(layer "F.SilkS")
		)
		(fp_line
			(start -0.7874 0.4064)
			(end -0.7874 -0.4064)
			(stroke
				(width 0.1524)
				(type default)
			)
			(layer "F.SilkS")
		)
		(fp_line
			(start 0.7874 -0.4064)
			(end 0.7874 0.4064)
			(stroke
				(width 0.1524)
				(type default)
			)
			(layer "F.SilkS")
		)
		(fp_line
			(start 0.7874 0.4064)
			(end -0.7874 0.4064)
			(stroke
				(width 0.1524)
				(type default)
			)
			(layer "F.SilkS")
		)
		(fp_line
			(start -0.67945 -0.305054)
			(end -0.12065 -0.305054)
			(stroke
				(width 0.1)
				(type default)
			)
			(layer "F.Fab")
		)
		(fp_line
			(start -0.67945 0.3048)
			(end -0.67945 -0.305054)
			(stroke
				(width 0.1)
				(type default)
			)
			(layer "F.Fab")
		)
		(fp_line
			(start -0.12065 -0.305054)
			(end -0.12065 -0.2794)
			(stroke
				(width 0.1)
				(type default)
			)
			(layer "F.Fab")
		)
		(fp_line
			(start -0.12065 -0.2794)
			(end 0.12065 -0.2794)
			(stroke
				(width 0.1)
				(type default)
			)
			(layer "F.Fab")
		)
		(fp_line
			(start -0.12065 0.2794)
			(end -0.12065 0.3048)
			(stroke
				(width 0.1)
				(type default)
			)
			(layer "F.Fab")
		)
		(fp_line
			(start -0.12065 0.3048)
			(end -0.67945 0.3048)
			(stroke
				(width 0.1)
				(type default)
			)
			(layer "F.Fab")
		)
		(fp_line
			(start 0.120396 0.2794)
			(end -0.12065 0.2794)
			(stroke
				(width 0.1)
				(type default)
			)
			(layer "F.Fab")
		)
		(fp_line
			(start 0.120396 0.3048)
			(end 0.120396 0.2794)
			(stroke
				(width 0.1)
				(type default)
			)
			(layer "F.Fab")
		)
		(fp_line
			(start 0.12065 -0.3048)
			(end 0.67945 -0.3048)
			(stroke
				(width 0.1)
				(type default)
			)
			(layer "F.Fab")
		)
		(fp_line
			(start 0.12065 -0.2794)
			(end 0.12065 -0.3048)
			(stroke
				(width 0.1)
				(type default)
			)
			(layer "F.Fab")
		)
		(fp_line
			(start 0.67945 -0.3048)
			(end 0.67945 0.3048)
			(stroke
				(width 0.1)
				(type default)
			)
			(layer "F.Fab")
		)
		(fp_line
			(start 0.67945 0.3048)
			(end 0.120396 0.3048)
			(stroke
				(width 0.1)
				(type default)
			)
			(layer "F.Fab")
		)
		(pad "1" smd circle
			(at -0.40005 0)
			(size 0 0)
			(layers "F.Cu" "F.Mask" "F.Paste")
			(net "P3V3_AUX_FB")
		)
		(pad "2" smd circle
			(at 0.40005 0)
			(size 0 0)
			(layers "F.Cu" "F.Mask" "F.Paste")
			(net "P3V3_AUX")
		)
	)
	(footprint ""
		(layer "F.Cu")
		(at 51.054 -5.207)
		(property "Reference" ""
			(at 0 0 0)
			(layer "F.SilkS")
			(hide yes)
			(effects
				(font
					(size 1.27 1.27)
				)
			)
		)
		(property "Value" ""
			(at 0 0 0)
			(layer "F.Fab")
			(effects
				(font
					(size 1.27 1.27)
				)
			)
		)
		(duplicate_pad_numbers_are_jumpers no)
		(pad "1" smd circle
			(at 0 0)
			(size 0.9906 0.9906)
			(layers "F.Cu" "F.Mask" "F.Paste")
			(net "Net_279")
		)
		(zone
			(layer "F.Cu")
			(hatch none 0.5)
			(connect_pads
				(clearance 0)
			)
			(min_thickness 0.25)
			(keepout
				(tracks not_allowed)
				(vias allowed)
				(pads allowed)
				(copperpour not_allowed)
				(footprints allowed)
			)
			(placement
				(enabled no)
				(sheetname "")
			)
			(fill
				(thermal_gap 0.5)
				(thermal_bridge_width 0.5)
				(island_removal_mode 0)
			)
			(polygon
				(pts
					(arc
						(start 52.6796 -5.207)
						(mid 49.4284 -5.207)
						(end 52.6796 -5.207)
					)
				)
			)
		)
	)
	(footprint ""
		(layer "F.Cu")
		(at 146.431 -7.747)
		(property "Reference" "ME5"
			(at 0 0 0)
			(layer "F.SilkS")
			(hide yes)
			(effects
				(font
					(size 1.27 1.27)
				)
			)
		)
		(property "Value" ""
			(at 0 0 0)
			(layer "F.Fab")
			(effects
				(font
					(size 1.27 1.27)
				)
			)
		)
		(duplicate_pad_numbers_are_jumpers no)
	)
	(footprint ""
		(layer "F.Cu")
		(at 82.046826 -136.906 90)
		(property "Reference" "PC45"
			(at 6.06933 1.011174 0)
			(unlocked yes)
			(layer "F.SilkS")
			(effects
				(font
					(size 0.7874 0.5842)
					(thickness 0.1524)
				)
				(justify left)
			)
		)
		(property "Value" ""
			(at 0 0 90)
			(layer "F.Fab")
			(effects
				(font
					(size 1.27 1.27)
				)
			)
		)
		(duplicate_pad_numbers_are_jumpers no)
		(fp_line
			(start 5.2578 2.499868)
			(end -5.2578 2.499868)
			(stroke
				(width 0.1524)
				(type default)
			)
			(layer "F.SilkS")
		)
		(fp_circle
			(center 0 2.500122)
			(end 0 7.758176)
			(stroke
				(width 0.1524)
				(type default)
			)
			(fill no)
			(layer "F.SilkS")
		)
		(fp_poly
			(pts
				(arc
					(start 5.2578 2.499868)
					(mid 0 7.757922)
					(end -5.2578 2.499868)
				)
			)
			(stroke
				(width 0)
				(type default)
			)
			(fill yes)
			(layer "F.SilkS")
		)
		(fp_circle
			(center 0 2.500122)
			(end 0 7.758176)
			(stroke
				(width 0.1)
				(type default)
			)
			(fill no)
			(layer "F.Fab")
		)
		(pad "1" thru_hole rect
			(at 0 0)
			(size 1.5748 1.5748)
			(drill 1.0668)
			(layers "*.Cu" "*.Mask")
			(remove_unused_layers no)
			(net "P52V_HS_FILTER")
			(clearance 0)
			(padstack
				(mode front_inner_back)
				(layer "Inner"
					(shape circle)
					(size 1.5748 1.5748)
					(clearance 0)
				)
				(layer "B.Cu"
					(shape rect)
					(size 1.5748 1.5748)
					(clearance 0)
				)
			)
		)
		(pad "2" thru_hole circle
			(at 0 4.99999)
			(size 1.5748 1.5748)
			(drill 1.0668)
			(layers "*.Cu" "*.Mask")
			(remove_unused_layers no)
			(net "GND")
			(clearance 0)
		)
	)
	(footprint ""
		(layer "F.Cu")
		(at 106.430826 -136.906 90)
		(property "Reference" "PC43"
			(at 6.06933 1.138174 0)
			(unlocked yes)
			(layer "F.SilkS")
			(effects
				(font
					(size 0.7874 0.5842)
					(thickness 0.1524)
				)
				(justify left)
			)
		)
		(property "Value" ""
			(at 0 0 90)
			(layer "F.Fab")
			(effects
				(font
					(size 1.27 1.27)
				)
			)
		)
		(duplicate_pad_numbers_are_jumpers no)
		(fp_line
			(start 5.2578 2.499868)
			(end -5.2578 2.499868)
			(stroke
				(width 0.1524)
				(type default)
			)
			(layer "F.SilkS")
		)
		(fp_circle
			(center 0 2.500122)
			(end 0 7.758176)
			(stroke
				(width 0.1524)
				(type default)
			)
			(fill no)
			(layer "F.SilkS")
		)
		(fp_poly
			(pts
				(arc
					(start 5.2578 2.499868)
					(mid 0 7.757922)
					(end -5.2578 2.499868)
				)
			)
			(stroke
				(width 0)
				(type default)
			)
			(fill yes)
			(layer "F.SilkS")
		)
		(fp_circle
			(center 0 2.500122)
			(end 0 7.758176)
			(stroke
				(width 0.1)
				(type default)
			)
			(fill no)
			(layer "F.Fab")
		)
		(pad "1" thru_hole rect
			(at 0 0)
			(size 1.5748 1.5748)
			(drill 1.0668)
			(layers "*.Cu" "*.Mask")
			(remove_unused_layers no)
			(net "P52V_HS_FILTER")
			(clearance 0)
			(padstack
				(mode front_inner_back)
				(layer "Inner"
					(shape circle)
					(size 1.5748 1.5748)
					(clearance 0)
				)
				(layer "B.Cu"
					(shape rect)
					(size 1.5748 1.5748)
					(clearance 0)
				)
			)
		)
		(pad "2" thru_hole circle
			(at 0 4.99999)
			(size 1.5748 1.5748)
			(drill 1.0668)
			(layers "*.Cu" "*.Mask")
			(remove_unused_layers no)
			(net "GND")
			(clearance 0)
		)
	)
	(footprint ""
		(layer "F.Cu")
		(at 297.561 -121.4755 180)
		(property "Reference" "PR6962"
			(at 0 0 180)
			(layer "F.SilkS")
			(hide yes)
			(effects
				(font
					(size 1.27 1.27)
				)
			)
		)
		(property "Value" ""
			(at 0 0 180)
			(layer "F.Fab")
			(effects
				(font
					(size 1.27 1.27)
				)
			)
		)
		(duplicate_pad_numbers_are_jumpers no)
		(fp_line
			(start 1.2954 0.5842)
			(end -1.2954 0.5842)
			(stroke
				(width 0.1524)
				(type default)
			)
			(layer "F.SilkS")
		)
		(fp_line
			(start 1.2954 -0.5842)
			(end 1.2954 0.5842)
			(stroke
				(width 0.1524)
				(type default)
			)
			(layer "F.SilkS")
		)
		(fp_line
			(start -1.2954 0.5842)
			(end -1.2954 -0.5842)
			(stroke
				(width 0.1524)
				(type default)
			)
			(layer "F.SilkS")
		)
		(fp_line
			(start -1.2954 -0.5842)
			(end 1.2954 -0.5842)
			(stroke
				(width 0.1524)
				(type default)
			)
			(layer "F.SilkS")
		)
		(fp_line
			(start 1.1938 0.4064)
			(end 0.8636 0.4064)
			(stroke
				(width 0.1)
				(type default)
			)
			(layer "F.Fab")
		)
		(fp_line
			(start 1.1938 -0.406654)
			(end 1.1938 0.4064)
			(stroke
				(width 0.1)
				(type default)
			)
			(layer "F.Fab")
		)
		(fp_line
			(start 0.8636 0.4572)
			(end -0.8636 0.4572)
			(stroke
				(width 0.1)
				(type default)
			)
			(layer "F.Fab")
		)
		(fp_line
			(start 0.8636 0.4064)
			(end 0.8636 0.4572)
			(stroke
				(width 0.1)
				(type default)
			)
			(layer "F.Fab")
		)
		(fp_line
			(start 0.8636 -0.406654)
			(end 1.1938 -0.406654)
			(stroke
				(width 0.1)
				(type default)
			)
			(layer "F.Fab")
		)
		(fp_line
			(start 0.8636 -0.4572)
			(end 0.8636 -0.406654)
			(stroke
				(width 0.1)
				(type default)
			)
			(layer "F.Fab")
		)
		(fp_line
			(start -0.8636 0.4572)
			(end -0.8636 0.4318)
			(stroke
				(width 0.1)
				(type default)
			)
			(layer "F.Fab")
		)
		(fp_line
			(start -0.8636 0.4318)
			(end -0.8636 0.4064)
			(stroke
				(width 0.1)
				(type default)
			)
			(layer "F.Fab")
		)
		(fp_line
			(start -0.8636 0.4064)
			(end -1.1938 0.4064)
			(stroke
				(width 0.1)
				(type default)
			)
			(layer "F.Fab")
		)
		(fp_line
			(start -0.8636 -0.406654)
			(end -0.8636 -0.4572)
			(stroke
				(width 0.1)
				(type default)
			)
			(layer "F.Fab")
		)
		(fp_line
			(start -0.8636 -0.4572)
			(end 0.8636 -0.4572)
			(stroke
				(width 0.1)
				(type default)
			)
			(layer "F.Fab")
		)
		(fp_line
			(start -1.1938 0.4064)
			(end -1.1938 -0.406654)
			(stroke
				(width 0.1)
				(type default)
			)
			(layer "F.Fab")
		)
		(fp_line
			(start -1.1938 -0.406654)
			(end -0.8636 -0.406654)
			(stroke
				(width 0.1)
				(type default)
			)
			(layer "F.Fab")
		)
		(pad "1" smd rect
			(at -0.7366 0 90)
			(size 0.7112 0.8128)
			(layers "F.Cu" "F.Mask" "F.Paste")
			(net "P52V_HS_4287_ADC_N")
		)
		(pad "2" smd rect
			(at 0.7366 0 90)
			(size 0.7112 0.8128)
			(layers "F.Cu" "F.Mask" "F.Paste")
			(net "P52V_HS1_SENSE_N_R1")
		)
	)
	(footprint ""
		(layer "F.Cu")
		(at 84.76488 -16.69288)
		(property "Reference" "ME4"
			(at 0 0 0)
			(layer "F.SilkS")
			(hide yes)
			(effects
				(font
					(size 1.27 1.27)
				)
			)
		)
		(property "Value" ""
			(at 0 0 0)
			(layer "F.Fab")
			(effects
				(font
					(size 1.27 1.27)
				)
			)
		)
		(duplicate_pad_numbers_are_jumpers no)
		(fp_line
			(start 0 -6.999986)
			(end 0 -5.475986)
			(stroke
				(width 0.1524)
				(type default)
			)
			(layer "F.SilkS")
		)
		(fp_line
			(start 0 -1.524)
			(end 0 0)
			(stroke
				(width 0.1524)
				(type default)
			)
			(layer "F.SilkS")
		)
		(fp_line
			(start 0 0)
			(end 1.524 0)
			(stroke
				(width 0.1524)
				(type default)
			)
			(layer "F.SilkS")
		)
		(fp_line
			(start 1.524 -6.999986)
			(end 0 -6.999986)
			(stroke
				(width 0.1524)
				(type default)
			)
			(layer "F.SilkS")
		)
		(fp_line
			(start 5.475986 -6.999986)
			(end 6.999986 -6.999986)
			(stroke
				(width 0.1524)
				(type default)
			)
			(layer "F.SilkS")
		)
		(fp_line
			(start 6.999986 -6.999986)
			(end 6.999986 -5.475986)
			(stroke
				(width 0.1524)
				(type default)
			)
			(layer "F.SilkS")
		)
		(fp_line
			(start 6.999986 -1.524)
			(end 6.999986 0)
			(stroke
				(width 0.1524)
				(type default)
			)
			(layer "F.SilkS")
		)
		(fp_line
			(start 6.999986 0)
			(end 5.475986 0)
			(stroke
				(width 0.1524)
				(type default)
			)
			(layer "F.SilkS")
		)
		(fp_text user "S/N"
			(at 0.361188 -5.450078 0)
			(unlocked yes)
			(layer "F.SilkS")
			(effects
				(font
					(size 1.905 1.4224)
					(thickness 0.1524)
				)
				(justify left)
			)
		)
	)
	(footprint ""
		(layer "F.Cu")
		(at 84.713826 -130.175)
		(property "Reference" "PC51"
			(at 0 0 0)
			(layer "F.SilkS")
			(hide yes)
			(effects
				(font
					(size 1.27 1.27)
				)
			)
		)
		(property "Value" ""
			(at 0 0 0)
			(layer "F.Fab")
			(effects
				(font
					(size 1.27 1.27)
				)
			)
		)
		(duplicate_pad_numbers_are_jumpers no)
		(fp_line
			(start -2.2098 -0.9398)
			(end 2.2098 -0.9398)
			(stroke
				(width 0.1524)
				(type default)
			)
			(layer "F.SilkS")
		)
		(fp_line
			(start -2.2098 0.9398)
			(end -2.2098 -0.9398)
			(stroke
				(width 0.1524)
				(type default)
			)
			(layer "F.SilkS")
		)
		(fp_line
			(start 2.2098 -0.9398)
			(end 2.2098 0.9398)
			(stroke
				(width 0.1524)
				(type default)
			)
			(layer "F.SilkS")
		)
		(fp_line
			(start 2.2098 0.9398)
			(end -2.2098 0.9398)
			(stroke
				(width 0.1524)
				(type default)
			)
			(layer "F.SilkS")
		)
		(fp_line
			(start -1.700022 -0.899922)
			(end 1.700022 -0.899922)
			(stroke
				(width 0.1)
				(type default)
			)
			(layer "F.Fab")
		)
		(fp_line
			(start -1.700022 0.899922)
			(end -1.700022 -0.899922)
			(stroke
				(width 0.1)
				(type default)
			)
			(layer "F.Fab")
		)
		(fp_line
			(start 1.700022 -0.899922)
			(end 1.700022 0.899922)
			(stroke
				(width 0.1)
				(type default)
			)
			(layer "F.Fab")
		)
		(fp_line
			(start 1.700022 0.899922)
			(end -1.700022 0.899922)
			(stroke
				(width 0.1)
				(type default)
			)
			(layer "F.Fab")
		)
		(pad "1" smd rect
			(at -1.4732 0 180)
			(size 1.1684 1.5748)
			(layers "F.Cu" "F.Mask" "F.Paste")
			(net "P52V_HS_FILTER")
		)
		(pad "2" smd rect
			(at 1.4732 0 180)
			(size 1.1684 1.5748)
			(layers "F.Cu" "F.Mask" "F.Paste")
			(net "GND")
		)
	)
	(footprint ""
		(layer "F.Cu")
		(at 282.78201 -56.957214 180)
		(property "Reference" "PR6968"
			(at 0 0 180)
			(layer "F.SilkS")
			(hide yes)
			(effects
				(font
					(size 1.27 1.27)
				)
			)
		)
		(property "Value" ""
			(at 0 0 180)
			(layer "F.Fab")
			(effects
				(font
					(size 1.27 1.27)
				)
			)
		)
		(duplicate_pad_numbers_are_jumpers no)
		(fp_line
			(start 0.7874 0.4064)
			(end -0.7874 0.4064)
			(stroke
				(width 0.1524)
				(type default)
			)
			(layer "F.SilkS")
		)
		(fp_line
			(start 0.7874 -0.4064)
			(end 0.7874 0.4064)
			(stroke
				(width 0.1524)
				(type default)
			)
			(layer "F.SilkS")
		)
		(fp_line
			(start -0.7874 0.4064)
			(end -0.7874 -0.4064)
			(stroke
				(width 0.1524)
				(type default)
			)
			(layer "F.SilkS")
		)
		(fp_line
			(start -0.7874 -0.4064)
			(end 0.7874 -0.4064)
			(stroke
				(width 0.1524)
				(type default)
			)
			(layer "F.SilkS")
		)
		(fp_line
			(start 0.67945 0.3048)
			(end 0.120396 0.3048)
			(stroke
				(width 0.1)
				(type default)
			)
			(layer "F.Fab")
		)
		(fp_line
			(start 0.67945 -0.3048)
			(end 0.67945 0.3048)
			(stroke
				(width 0.1)
				(type default)
			)
			(layer "F.Fab")
		)
		(fp_line
			(start 0.12065 -0.2794)
			(end 0.12065 -0.3048)
			(stroke
				(width 0.1)
				(type default)
			)
			(layer "F.Fab")
		)
		(fp_line
			(start 0.12065 -0.3048)
			(end 0.67945 -0.3048)
			(stroke
				(width 0.1)
				(type default)
			)
			(layer "F.Fab")
		)
		(fp_line
			(start 0.120396 0.3048)
			(end 0.120396 0.2794)
			(stroke
				(width 0.1)
				(type default)
			)
			(layer "F.Fab")
		)
		(fp_line
			(start 0.120396 0.2794)
			(end -0.12065 0.2794)
			(stroke
				(width 0.1)
				(type default)
			)
			(layer "F.Fab")
		)
		(fp_line
			(start -0.12065 0.3048)
			(end -0.67945 0.3048)
			(stroke
				(width 0.1)
				(type default)
			)
			(layer "F.Fab")
		)
		(fp_line
			(start -0.12065 0.2794)
			(end -0.12065 0.3048)
			(stroke
				(width 0.1)
				(type default)
			)
			(layer "F.Fab")
		)
		(fp_line
			(start -0.12065 -0.2794)
			(end 0.12065 -0.2794)
			(stroke
				(width 0.1)
				(type default)
			)
			(layer "F.Fab")
		)
		(fp_line
			(start -0.12065 -0.305054)
			(end -0.12065 -0.2794)
			(stroke
				(width 0.1)
				(type default)
			)
			(layer "F.Fab")
		)
		(fp_line
			(start -0.67945 0.3048)
			(end -0.67945 -0.305054)
			(stroke
				(width 0.1)
				(type default)
			)
			(layer "F.Fab")
		)
		(fp_line
			(start -0.67945 -0.305054)
			(end -0.12065 -0.305054)
			(stroke
				(width 0.1)
				(type default)
			)
			(layer "F.Fab")
		)
		(pad "1" smd rect
			(at -0.40005 0)
			(size 0.4572 0.508)
			(layers "F.Cu" "F.Mask" "F.Paste")
			(net "P52V_HS1_TEMPN")
		)
		(pad "2" smd rect
			(at 0.40005 0)
			(size 0.4572 0.508)
			(layers "F.Cu" "F.Mask" "F.Paste")
			(net "P52V_HS1_TEMPN_R")
		)
	)
)
